# T6G (Grand Teton) — schematic netlist excerpt (pin names and nets, part order shuffled) for the footprints in the layout excerpt that follows; sources: Cadence DE-HDL packaged netlist, KiCad conversion of 04192023_DAF0TMB3IC0_F0TG_MB_C_brd_V02_OCP.brd

R6245  Q_RES  0 5% CHIP  pkg 0402LF  page 270 : A = P3V3_AUX ; B = P1V2_AUX_VCC
R1236  Q_RES  5.11K 1% CHIP  pkg 0402LF  page 258 : A = PVDD18_S5_P1 ; B = PVDD18_S5_P1_ADC

(kicad_pcb
	(version 20260206)
	(generator "pcbnew")
	(generator_version "10.0")
	(general
		(thickness 1.6)
		(legacy_teardrops no)
	)
	(paper "A4")
	(title_block
		(title "04192023_DAF0TMB3IC0_F0TG_MB_C_brd_V02_OCP.brd")
		(comment 1 "Grand Teton / footprints 6544-6545 of 8354")
	)
	(layers
		(0 "F.Cu" signal "TOP")
		(4 "In1.Cu" signal "GND")
		(6 "In2.Cu" signal "IN1")
		(8 "In3.Cu" signal "GND1")
		(10 "In4.Cu" signal "IN2")
		(12 "In5.Cu" signal "GND2")
		(14 "In6.Cu" signal "IN3")
		(16 "In7.Cu" signal "GND3")
		(18 "In8.Cu" signal "VCC")
		(20 "In9.Cu" signal "VCC1")
		(22 "In10.Cu" signal "GND4")
		(24 "In11.Cu" signal "IN4")
		(26 "In12.Cu" signal "GND5")
		(28 "In13.Cu" signal "IN5")
		(30 "In14.Cu" signal "GND6")
		(32 "In15.Cu" signal "IN6")
		(34 "In16.Cu" signal "GND7")
		(2 "B.Cu" signal "BOTTOM")
		(9 "F.Adhes" user "F.Adhesive")
		(11 "B.Adhes" user "B.Adhesive")
		(13 "F.Paste" user "Package Geometry/Pastemask Top")
		(15 "B.Paste" user "Package Geometry/Pastemask Bottom")
		(5 "F.SilkS" user "Ref Des/Silkscreen Top")
		(7 "B.SilkS" user "Ref Des/Silkscreen Bottom")
		(1 "F.Mask" user "Board Geometry/Soldermask Top")
		(3 "B.Mask" user "Board Geometry/Soldermask Bottom")
		(17 "Dwgs.User" user "User.Drawings")
		(19 "Cmts.User" user "User.Comments")
		(21 "Eco1.User" user "User.Eco1")
		(23 "Eco2.User" user "User.Eco2")
		(25 "Edge.Cuts" user "Board Geometry/Outline")
		(27 "Margin" user)
		(31 "F.CrtYd" user "Package Geometry/Place Bound Top")
		(29 "B.CrtYd" user "Package Geometry/Place Bound Bottom")
		(35 "F.Fab" user "Ref Des/Assembly Top")
		(33 "B.Fab" user "Ref Des/Assembly Bottom")
	)
	(footprint ""
		(layer "B.Cu")
		(at 121.066306 -79.737458 90)
		(property "Reference" "R6245"
			(at 0 0 90)
			(layer "B.SilkS")
			(hide yes)
			(effects
				(font
					(size 1.27 1.27)
				)
				(justify mirror)
			)
		)
		(property "Value" ""
			(at 0 0 90)
			(layer "B.Fab")
			(effects
				(font
					(size 1.27 1.27)
				)
				(justify mirror)
			)
		)
		(duplicate_pad_numbers_are_jumpers no)
		(fp_line
			(start 0.7874 -0.4064)
			(end -0.7874 -0.4064)
			(stroke
				(width 0.1524)
				(type default)
			)
			(layer "B.SilkS")
		)
		(fp_line
			(start -0.7874 -0.4064)
			(end -0.7874 0.4064)
			(stroke
				(width 0.1524)
				(type default)
			)
			(layer "B.SilkS")
		)
		(fp_line
			(start 0.7874 0.4064)
			(end 0.7874 -0.4064)
			(stroke
				(width 0.1524)
				(type default)
			)
			(layer "B.SilkS")
		)
		(fp_line
			(start -0.7874 0.4064)
			(end 0.7874 0.4064)
			(stroke
				(width 0.1524)
				(type default)
			)
			(layer "B.SilkS")
		)
		(fp_line
			(start 0.67945 -0.305054)
			(end 0.12065 -0.305054)
			(stroke
				(width 0.1)
				(type default)
			)
			(layer "B.Fab")
		)
		(fp_line
			(start 0.12065 -0.305054)
			(end 0.12065 -0.2794)
			(stroke
				(width 0.1)
				(type default)
			)
			(layer "B.Fab")
		)
		(fp_line
			(start -0.12065 -0.3048)
			(end -0.67945 -0.3048)
			(stroke
				(width 0.1)
				(type default)
			)
			(layer "B.Fab")
		)
		(fp_line
			(start -0.67945 -0.3048)
			(end -0.67945 0.3048)
			(stroke
				(width 0.1)
				(type default)
			)
			(layer "B.Fab")
		)
		(fp_line
			(start 0.12065 -0.2794)
			(end -0.12065 -0.2794)
			(stroke
				(width 0.1)
				(type default)
			)
			(layer "B.Fab")
		)
		(fp_line
			(start -0.12065 -0.2794)
			(end -0.12065 -0.3048)
			(stroke
				(width 0.1)
				(type default)
			)
			(layer "B.Fab")
		)
		(fp_line
			(start 0.12065 0.2794)
			(end 0.12065 0.3048)
			(stroke
				(width 0.1)
				(type default)
			)
			(layer "B.Fab")
		)
		(fp_line
			(start -0.120396 0.2794)
			(end 0.12065 0.2794)
			(stroke
				(width 0.1)
				(type default)
			)
			(layer "B.Fab")
		)
		(fp_line
			(start 0.67945 0.3048)
			(end 0.67945 -0.305054)
			(stroke
				(width 0.1)
				(type default)
			)
			(layer "B.Fab")
		)
		(fp_line
			(start 0.12065 0.3048)
			(end 0.67945 0.3048)
			(stroke
				(width 0.1)
				(type default)
			)
			(layer "B.Fab")
		)
		(fp_line
			(start -0.120396 0.3048)
			(end -0.120396 0.2794)
			(stroke
				(width 0.1)
				(type default)
			)
			(layer "B.Fab")
		)
		(fp_line
			(start -0.67945 0.3048)
			(end -0.120396 0.3048)
			(stroke
				(width 0.1)
				(type default)
			)
			(layer "B.Fab")
		)
		(pad "1" smd circle
			(at 0.40005 0 270)
			(size 0 0)
			(layers "B.Cu" "B.Mask" "B.Paste")
			(net "P3V3_AUX")
		)
		(pad "2" smd circle
			(at -0.40005 0 270)
			(size 0 0)
			(layers "B.Cu" "B.Mask" "B.Paste")
			(net "P1V2_AUX_VCC")
		)
	)
	(footprint ""
		(layer "B.Cu")
		(at 237.88116 -328.724514)
		(property "Reference" "R1236"
			(at 0 0 0)
			(layer "B.SilkS")
			(hide yes)
			(effects
				(font
					(size 1.27 1.27)
				)
				(justify mirror)
			)
		)
		(property "Value" ""
			(at 0 0 0)
			(layer "B.Fab")
			(effects
				(font
					(size 1.27 1.27)
				)
				(justify mirror)
			)
		)
		(duplicate_pad_numbers_are_jumpers no)
		(fp_line
			(start -0.7874 -0.4064)
			(end -0.7874 0.4064)
			(stroke
				(width 0.1524)
				(type default)
			)
			(layer "B.SilkS")
		)
		(fp_line
			(start -0.7874 0.4064)
			(end 0.7874 0.4064)
			(stroke
				(width 0.1524)
				(type default)
			)
			(layer "B.SilkS")
		)
		(fp_line
			(start 0.7874 -0.4064)
			(end -0.7874 -0.4064)
			(stroke
				(width 0.1524)
				(type default)
			)
			(layer "B.SilkS")
		)
		(fp_line
			(start 0.7874 0.4064)
			(end 0.7874 -0.4064)
			(stroke
				(width 0.1524)
				(type default)
			)
			(layer "B.SilkS")
		)
		(fp_line
			(start -0.67945 -0.3048)
			(end -0.67945 0.3048)
			(stroke
				(width 0.1)
				(type default)
			)
			(layer "B.Fab")
		)
		(fp_line
			(start -0.67945 0.3048)
			(end -0.120396 0.3048)
			(stroke
				(width 0.1)
				(type default)
			)
			(layer "B.Fab")
		)
		(fp_line
			(start -0.12065 -0.3048)
			(end -0.67945 -0.3048)
			(stroke
				(width 0.1)
				(type default)
			)
			(layer "B.Fab")
		)
		(fp_line
			(start -0.12065 -0.2794)
			(end -0.12065 -0.3048)
			(stroke
				(width 0.1)
				(type default)
			)
			(layer "B.Fab")
		)
		(fp_line
			(start -0.120396 0.2794)
			(end 0.12065 0.2794)
			(stroke
				(width 0.1)
				(type default)
			)
			(layer "B.Fab")
		)
		(fp_line
			(start -0.120396 0.3048)
			(end -0.120396 0.2794)
			(stroke
				(width 0.1)
				(type default)
			)
			(layer "B.Fab")
		)
		(fp_line
			(start 0.12065 -0.305054)
			(end 0.12065 -0.2794)
			(stroke
				(width 0.1)
				(type default)
			)
			(layer "B.Fab")
		)
		(fp_line
			(start 0.12065 -0.2794)
			(end -0.12065 -0.2794)
			(stroke
				(width 0.1)
				(type default)
			)
			(layer "B.Fab")
		)
		(fp_line
			(start 0.12065 0.2794)
			(end 0.12065 0.3048)
			(stroke
				(width 0.1)
				(type default)
			)
			(layer "B.Fab")
		)
		(fp_line
			(start 0.12065 0.3048)
			(end 0.67945 0.3048)
			(stroke
				(width 0.1)
				(type default)
			)
			(layer "B.Fab")
		)
		(fp_line
			(start 0.67945 -0.305054)
			(end 0.12065 -0.305054)
			(stroke
				(width 0.1)
				(type default)
			)
			(layer "B.Fab")
		)
		(fp_line
			(start 0.67945 0.3048)
			(end 0.67945 -0.305054)
			(stroke
				(width 0.1)
				(type default)
			)
			(layer "B.Fab")
		)
		(pad "1" smd circle
			(at 0.40005 0 180)
			(size 0 0)
			(layers "B.Cu" "B.Mask" "B.Paste")
			(net "PVDD18_S5_P1")
		)
		(pad "2" smd circle
			(at -0.40005 0 180)
			(size 0 0)
			(layers "B.Cu" "B.Mask" "B.Paste")
			(net "PVDD18_S5_P1_ADC")
		)
	)
)
